# T6G (Grand Teton) — schematic netlist excerpt (pin names and nets, part order shuffled) for the footprints in the layout excerpt that follows; sources: Cadence DE-HDL packaged netlist, KiCad conversion of 04192023_DAF0TMB3IC0_F0TG_MB_C_brd_V02_OCP.brd

R27  Q_RES  0 5% CHIP  pkg 0402LF  page 28 : A = SMB_CPU0_2_R_SCL ; B = SMB_CPU0_2_SCL
R1222  Q_RES  18K 1% CHIP  pkg 0402LF  page 258 : A = PVDD18_S5_P0_ADC ; B = GND

(kicad_pcb
	(version 20260206)
	(generator "pcbnew")
	(generator_version "10.0")
	(general
		(thickness 1.6)
		(legacy_teardrops no)
	)
	(paper "A4")
	(title_block
		(title "04192023_DAF0TMB3IC0_F0TG_MB_C_brd_V02_OCP.brd")
		(comment 1 "Grand Teton / footprints 8349-8350 of 8354")
	)
	(layers
		(0 "F.Cu" signal "TOP")
		(4 "In1.Cu" signal "GND")
		(6 "In2.Cu" signal "IN1")
		(8 "In3.Cu" signal "GND1")
		(10 "In4.Cu" signal "IN2")
		(12 "In5.Cu" signal "GND2")
		(14 "In6.Cu" signal "IN3")
		(16 "In7.Cu" signal "GND3")
		(18 "In8.Cu" signal "VCC")
		(20 "In9.Cu" signal "VCC1")
		(22 "In10.Cu" signal "GND4")
		(24 "In11.Cu" signal "IN4")
		(26 "In12.Cu" signal "GND5")
		(28 "In13.Cu" signal "IN5")
		(30 "In14.Cu" signal "GND6")
		(32 "In15.Cu" signal "IN6")
		(34 "In16.Cu" signal "GND7")
		(2 "B.Cu" signal "BOTTOM")
		(9 "F.Adhes" user "F.Adhesive")
		(11 "B.Adhes" user "B.Adhesive")
		(13 "F.Paste" user "Package Geometry/Pastemask Top")
		(15 "B.Paste" user "Package Geometry/Pastemask Bottom")
		(5 "F.SilkS" user "Ref Des/Silkscreen Top")
		(7 "B.SilkS" user "Ref Des/Silkscreen Bottom")
		(1 "F.Mask" user "Board Geometry/Soldermask Top")
		(3 "B.Mask" user "Board Geometry/Soldermask Bottom")
		(17 "Dwgs.User" user "User.Drawings")
		(19 "Cmts.User" user "User.Comments")
		(21 "Eco1.User" user "User.Eco1")
		(23 "Eco2.User" user "User.Eco2")
		(25 "Edge.Cuts" user "Board Geometry/Outline")
		(27 "Margin" user)
		(31 "F.CrtYd" user "Package Geometry/Place Bound Top")
		(29 "B.CrtYd" user "Package Geometry/Place Bound Bottom")
		(35 "F.Fab" user "Ref Des/Assembly Top")
		(33 "B.Fab" user "Ref Des/Assembly Bottom")
	)
	(footprint ""
		(layer "B.Cu")
		(at 234.825286 -328.085704 180)
		(property "Reference" "R1222"
			(at 0 0 0)
			(layer "B.SilkS")
			(hide yes)
			(effects
				(font
					(size 1.27 1.27)
				)
				(justify mirror)
			)
		)
		(property "Value" ""
			(at 0 0 0)
			(layer "B.Fab")
			(effects
				(font
					(size 1.27 1.27)
				)
				(justify mirror)
			)
		)
		(duplicate_pad_numbers_are_jumpers no)
		(fp_line
			(start 0.7874 0.4064)
			(end 0.7874 -0.4064)
			(stroke
				(width 0.1524)
				(type default)
			)
			(layer "B.SilkS")
		)
		(fp_line
			(start 0.7874 -0.4064)
			(end -0.7874 -0.4064)
			(stroke
				(width 0.1524)
				(type default)
			)
			(layer "B.SilkS")
		)
		(fp_line
			(start -0.7874 0.4064)
			(end 0.7874 0.4064)
			(stroke
				(width 0.1524)
				(type default)
			)
			(layer "B.SilkS")
		)
		(fp_line
			(start -0.7874 -0.4064)
			(end -0.7874 0.4064)
			(stroke
				(width 0.1524)
				(type default)
			)
			(layer "B.SilkS")
		)
		(fp_line
			(start 0.67945 0.3048)
			(end 0.67945 -0.305054)
			(stroke
				(width 0.1)
				(type default)
			)
			(layer "B.Fab")
		)
		(fp_line
			(start 0.67945 -0.305054)
			(end 0.12065 -0.305054)
			(stroke
				(width 0.1)
				(type default)
			)
			(layer "B.Fab")
		)
		(fp_line
			(start 0.12065 0.3048)
			(end 0.67945 0.3048)
			(stroke
				(width 0.1)
				(type default)
			)
			(layer "B.Fab")
		)
		(fp_line
			(start 0.12065 0.2794)
			(end 0.12065 0.3048)
			(stroke
				(width 0.1)
				(type default)
			)
			(layer "B.Fab")
		)
		(fp_line
			(start 0.12065 -0.2794)
			(end -0.12065 -0.2794)
			(stroke
				(width 0.1)
				(type default)
			)
			(layer "B.Fab")
		)
		(fp_line
			(start 0.12065 -0.305054)
			(end 0.12065 -0.2794)
			(stroke
				(width 0.1)
				(type default)
			)
			(layer "B.Fab")
		)
		(fp_line
			(start -0.120396 0.3048)
			(end -0.120396 0.2794)
			(stroke
				(width 0.1)
				(type default)
			)
			(layer "B.Fab")
		)
		(fp_line
			(start -0.120396 0.2794)
			(end 0.12065 0.2794)
			(stroke
				(width 0.1)
				(type default)
			)
			(layer "B.Fab")
		)
		(fp_line
			(start -0.12065 -0.2794)
			(end -0.12065 -0.3048)
			(stroke
				(width 0.1)
				(type default)
			)
			(layer "B.Fab")
		)
		(fp_line
			(start -0.12065 -0.3048)
			(end -0.67945 -0.3048)
			(stroke
				(width 0.1)
				(type default)
			)
			(layer "B.Fab")
		)
		(fp_line
			(start -0.67945 0.3048)
			(end -0.120396 0.3048)
			(stroke
				(width 0.1)
				(type default)
			)
			(layer "B.Fab")
		)
		(fp_line
			(start -0.67945 -0.3048)
			(end -0.67945 0.3048)
			(stroke
				(width 0.1)
				(type default)
			)
			(layer "B.Fab")
		)
		(pad "1" smd circle
			(at 0.40005 0)
			(size 0 0)
			(layers "B.Cu" "B.Mask" "B.Paste")
			(net "PVDD18_S5_P0_ADC")
		)
		(pad "2" smd circle
			(at -0.40005 0)
			(size 0 0)
			(layers "B.Cu" "B.Mask" "B.Paste")
			(net "GND")
		)
	)
	(footprint ""
		(layer "B.Cu")
		(at 315.004958 -201.926952 90)
		(property "Reference" "R27"
			(at 0 0 90)
			(layer "B.SilkS")
			(hide yes)
			(effects
				(font
					(size 1.27 1.27)
				)
				(justify mirror)
			)
		)
		(property "Value" ""
			(at 0 0 90)
			(layer "B.Fab")
			(effects
				(font
					(size 1.27 1.27)
				)
				(justify mirror)
			)
		)
		(duplicate_pad_numbers_are_jumpers no)
		(fp_line
			(start 0.7874 -0.4064)
			(end -0.7874 -0.4064)
			(stroke
				(width 0.1524)
				(type default)
			)
			(layer "B.SilkS")
		)
		(fp_line
			(start -0.7874 -0.4064)
			(end -0.7874 0.4064)
			(stroke
				(width 0.1524)
				(type default)
			)
			(layer "B.SilkS")
		)
		(fp_line
			(start 0.7874 0.4064)
			(end 0.7874 -0.4064)
			(stroke
				(width 0.1524)
				(type default)
			)
			(layer "B.SilkS")
		)
		(fp_line
			(start -0.7874 0.4064)
			(end 0.7874 0.4064)
			(stroke
				(width 0.1524)
				(type default)
			)
			(layer "B.SilkS")
		)
		(fp_line
			(start 0.67945 -0.305054)
			(end 0.12065 -0.305054)
			(stroke
				(width 0.1)
				(type default)
			)
			(layer "B.Fab")
		)
		(fp_line
			(start 0.12065 -0.305054)
			(end 0.12065 -0.2794)
			(stroke
				(width 0.1)
				(type default)
			)
			(layer "B.Fab")
		)
		(fp_line
			(start -0.12065 -0.3048)
			(end -0.67945 -0.3048)
			(stroke
				(width 0.1)
				(type default)
			)
			(layer "B.Fab")
		)
		(fp_line
			(start -0.67945 -0.3048)
			(end -0.67945 0.3048)
			(stroke
				(width 0.1)
				(type default)
			)
			(layer "B.Fab")
		)
		(fp_line
			(start 0.12065 -0.2794)
			(end -0.12065 -0.2794)
			(stroke
				(width 0.1)
				(type default)
			)
			(layer "B.Fab")
		)
		(fp_line
			(start -0.12065 -0.2794)
			(end -0.12065 -0.3048)
			(stroke
				(width 0.1)
				(type default)
			)
			(layer "B.Fab")
		)
		(fp_line
			(start 0.12065 0.2794)
			(end 0.12065 0.3048)
			(stroke
				(width 0.1)
				(type default)
			)
			(layer "B.Fab")
		)
		(fp_line
			(start -0.120396 0.2794)
			(end 0.12065 0.2794)
			(stroke
				(width 0.1)
				(type default)
			)
			(layer "B.Fab")
		)
		(fp_line
			(start 0.67945 0.3048)
			(end 0.67945 -0.305054)
			(stroke
				(width 0.1)
				(type default)
			)
			(layer "B.Fab")
		)
		(fp_line
			(start 0.12065 0.3048)
			(end 0.67945 0.3048)
			(stroke
				(width 0.1)
				(type default)
			)
			(layer "B.Fab")
		)
		(fp_line
			(start -0.120396 0.3048)
			(end -0.120396 0.2794)
			(stroke
				(width 0.1)
				(type default)
			)
			(layer "B.Fab")
		)
		(fp_line
			(start -0.67945 0.3048)
			(end -0.120396 0.3048)
			(stroke
				(width 0.1)
				(type default)
			)
			(layer "B.Fab")
		)
		(pad "1" smd circle
			(at 0.40005 0 270)
			(size 0 0)
			(layers "B.Cu" "B.Mask" "B.Paste")
			(net "SMB_CPU0_2_R_SCL")
		)
		(pad "2" smd circle
			(at -0.40005 0 270)
			(size 0 0)
			(layers "B.Cu" "B.Mask" "B.Paste")
			(net "SMB_CPU0_2_SCL")
		)
	)
)
